# T6G (Grand Teton) — schematic netlist excerpt (pin names and nets, part order shuffled) for the footprints in the layout excerpt that follows; sources: Cadence DE-HDL packaged netlist, KiCad conversion of 04192023_DAF0TMB3IC0_F0TG_MB_C_brd_V02_OCP.brd

R373  Q_RES  0 5% EMPTY  pkg 0402LF  page 57 : A = P1V5_BAT ; B = CPU1_VDDBT_RTC_G
PR359  Q_RES  8.87K 1% EMPTY  pkg 0402LF  page 198 : A = GND ; B = PVDDCR_SOC_P0_LSET2

(kicad_pcb
	(version 20260206)
	(generator "pcbnew")
	(generator_version "10.0")
	(general
		(thickness 1.6)
		(legacy_teardrops no)
	)
	(paper "A4")
	(title_block
		(title "04192023_DAF0TMB3IC0_F0TG_MB_C_brd_V02_OCP.brd")
		(comment 1 "Grand Teton / footprints 4913-4914 of 8354")
	)
	(layers
		(0 "F.Cu" signal "TOP")
		(4 "In1.Cu" signal "GND")
		(6 "In2.Cu" signal "IN1")
		(8 "In3.Cu" signal "GND1")
		(10 "In4.Cu" signal "IN2")
		(12 "In5.Cu" signal "GND2")
		(14 "In6.Cu" signal "IN3")
		(16 "In7.Cu" signal "GND3")
		(18 "In8.Cu" signal "VCC")
		(20 "In9.Cu" signal "VCC1")
		(22 "In10.Cu" signal "GND4")
		(24 "In11.Cu" signal "IN4")
		(26 "In12.Cu" signal "GND5")
		(28 "In13.Cu" signal "IN5")
		(30 "In14.Cu" signal "GND6")
		(32 "In15.Cu" signal "IN6")
		(34 "In16.Cu" signal "GND7")
		(2 "B.Cu" signal "BOTTOM")
		(9 "F.Adhes" user "F.Adhesive")
		(11 "B.Adhes" user "B.Adhesive")
		(13 "F.Paste" user "Package Geometry/Pastemask Top")
		(15 "B.Paste" user "Package Geometry/Pastemask Bottom")
		(5 "F.SilkS" user "Ref Des/Silkscreen Top")
		(7 "B.SilkS" user "Ref Des/Silkscreen Bottom")
		(1 "F.Mask" user "Board Geometry/Soldermask Top")
		(3 "B.Mask" user "Board Geometry/Soldermask Bottom")
		(17 "Dwgs.User" user "User.Drawings")
		(19 "Cmts.User" user "User.Comments")
		(21 "Eco1.User" user "User.Eco1")
		(23 "Eco2.User" user "User.Eco2")
		(25 "Edge.Cuts" user "Board Geometry/Outline")
		(27 "Margin" user)
		(31 "F.CrtYd" user "Package Geometry/Place Bound Top")
		(29 "B.CrtYd" user "Package Geometry/Place Bound Bottom")
		(35 "F.Fab" user "Ref Des/Assembly Top")
		(33 "B.Fab" user "Ref Des/Assembly Bottom")
	)
	(footprint ""
		(layer "F.Cu")
		(at 407.452322 -163.382198)
		(property "Reference" "PR359"
			(at 0 0 0)
			(layer "F.SilkS")
			(hide yes)
			(effects
				(font
					(size 1.27 1.27)
				)
			)
		)
		(property "Value" ""
			(at 0 0 0)
			(layer "F.Fab")
			(effects
				(font
					(size 1.27 1.27)
				)
			)
		)
		(duplicate_pad_numbers_are_jumpers no)
		(fp_line
			(start -0.7874 -0.4064)
			(end 0.7874 -0.4064)
			(stroke
				(width 0.1524)
				(type default)
			)
			(layer "F.SilkS")
		)
		(fp_line
			(start -0.7874 0.4064)
			(end -0.7874 -0.4064)
			(stroke
				(width 0.1524)
				(type default)
			)
			(layer "F.SilkS")
		)
		(fp_line
			(start 0.7874 -0.4064)
			(end 0.7874 0.4064)
			(stroke
				(width 0.1524)
				(type default)
			)
			(layer "F.SilkS")
		)
		(fp_line
			(start 0.7874 0.4064)
			(end -0.7874 0.4064)
			(stroke
				(width 0.1524)
				(type default)
			)
			(layer "F.SilkS")
		)
		(fp_line
			(start -0.67945 -0.305054)
			(end -0.12065 -0.305054)
			(stroke
				(width 0.1)
				(type default)
			)
			(layer "F.Fab")
		)
		(fp_line
			(start -0.67945 0.3048)
			(end -0.67945 -0.305054)
			(stroke
				(width 0.1)
				(type default)
			)
			(layer "F.Fab")
		)
		(fp_line
			(start -0.12065 -0.305054)
			(end -0.12065 -0.2794)
			(stroke
				(width 0.1)
				(type default)
			)
			(layer "F.Fab")
		)
		(fp_line
			(start -0.12065 -0.2794)
			(end 0.12065 -0.2794)
			(stroke
				(width 0.1)
				(type default)
			)
			(layer "F.Fab")
		)
		(fp_line
			(start -0.12065 0.2794)
			(end -0.12065 0.3048)
			(stroke
				(width 0.1)
				(type default)
			)
			(layer "F.Fab")
		)
		(fp_line
			(start -0.12065 0.3048)
			(end -0.67945 0.3048)
			(stroke
				(width 0.1)
				(type default)
			)
			(layer "F.Fab")
		)
		(fp_line
			(start 0.120396 0.2794)
			(end -0.12065 0.2794)
			(stroke
				(width 0.1)
				(type default)
			)
			(layer "F.Fab")
		)
		(fp_line
			(start 0.120396 0.3048)
			(end 0.120396 0.2794)
			(stroke
				(width 0.1)
				(type default)
			)
			(layer "F.Fab")
		)
		(fp_line
			(start 0.12065 -0.3048)
			(end 0.67945 -0.3048)
			(stroke
				(width 0.1)
				(type default)
			)
			(layer "F.Fab")
		)
		(fp_line
			(start 0.12065 -0.2794)
			(end 0.12065 -0.3048)
			(stroke
				(width 0.1)
				(type default)
			)
			(layer "F.Fab")
		)
		(fp_line
			(start 0.67945 -0.3048)
			(end 0.67945 0.3048)
			(stroke
				(width 0.1)
				(type default)
			)
			(layer "F.Fab")
		)
		(fp_line
			(start 0.67945 0.3048)
			(end 0.120396 0.3048)
			(stroke
				(width 0.1)
				(type default)
			)
			(layer "F.Fab")
		)
		(pad "1" smd circle
			(at -0.40005 0)
			(size 0 0)
			(layers "F.Cu" "F.Mask" "F.Paste")
			(net "GND")
		)
		(pad "2" smd circle
			(at 0.40005 0)
			(size 0 0)
			(layers "F.Cu" "F.Mask" "F.Paste")
			(net "PVDDCR_SOC_P0_LSET2")
		)
	)
	(footprint ""
		(layer "F.Cu")
		(at 149.649434 -321.733672 180)
		(property "Reference" "R373"
			(at 0 0 180)
			(layer "F.SilkS")
			(hide yes)
			(effects
				(font
					(size 1.27 1.27)
				)
			)
		)
		(property "Value" ""
			(at 0 0 180)
			(layer "F.Fab")
			(effects
				(font
					(size 1.27 1.27)
				)
			)
		)
		(duplicate_pad_numbers_are_jumpers no)
		(fp_line
			(start 0.7874 0.4064)
			(end -0.7874 0.4064)
			(stroke
				(width 0.1524)
				(type default)
			)
			(layer "F.SilkS")
		)
		(fp_line
			(start 0.7874 -0.4064)
			(end 0.7874 0.4064)
			(stroke
				(width 0.1524)
				(type default)
			)
			(layer "F.SilkS")
		)
		(fp_line
			(start -0.7874 0.4064)
			(end -0.7874 -0.4064)
			(stroke
				(width 0.1524)
				(type default)
			)
			(layer "F.SilkS")
		)
		(fp_line
			(start -0.7874 -0.4064)
			(end 0.7874 -0.4064)
			(stroke
				(width 0.1524)
				(type default)
			)
			(layer "F.SilkS")
		)
		(fp_line
			(start 0.67945 0.3048)
			(end 0.120396 0.3048)
			(stroke
				(width 0.1)
				(type default)
			)
			(layer "F.Fab")
		)
		(fp_line
			(start 0.67945 -0.3048)
			(end 0.67945 0.3048)
			(stroke
				(width 0.1)
				(type default)
			)
			(layer "F.Fab")
		)
		(fp_line
			(start 0.12065 -0.2794)
			(end 0.12065 -0.3048)
			(stroke
				(width 0.1)
				(type default)
			)
			(layer "F.Fab")
		)
		(fp_line
			(start 0.12065 -0.3048)
			(end 0.67945 -0.3048)
			(stroke
				(width 0.1)
				(type default)
			)
			(layer "F.Fab")
		)
		(fp_line
			(start 0.120396 0.3048)
			(end 0.120396 0.2794)
			(stroke
				(width 0.1)
				(type default)
			)
			(layer "F.Fab")
		)
		(fp_line
			(start 0.120396 0.2794)
			(end -0.12065 0.2794)
			(stroke
				(width 0.1)
				(type default)
			)
			(layer "F.Fab")
		)
		(fp_line
			(start -0.12065 0.3048)
			(end -0.67945 0.3048)
			(stroke
				(width 0.1)
				(type default)
			)
			(layer "F.Fab")
		)
		(fp_line
			(start -0.12065 0.2794)
			(end -0.12065 0.3048)
			(stroke
				(width 0.1)
				(type default)
			)
			(layer "F.Fab")
		)
		(fp_line
			(start -0.12065 -0.2794)
			(end 0.12065 -0.2794)
			(stroke
				(width 0.1)
				(type default)
			)
			(layer "F.Fab")
		)
		(fp_line
			(start -0.12065 -0.305054)
			(end -0.12065 -0.2794)
			(stroke
				(width 0.1)
				(type default)
			)
			(layer "F.Fab")
		)
		(fp_line
			(start -0.67945 0.3048)
			(end -0.67945 -0.305054)
			(stroke
				(width 0.1)
				(type default)
			)
			(layer "F.Fab")
		)
		(fp_line
			(start -0.67945 -0.305054)
			(end -0.12065 -0.305054)
			(stroke
				(width 0.1)
				(type default)
			)
			(layer "F.Fab")
		)
		(pad "1" smd circle
			(at -0.40005 0 180)
			(size 0 0)
			(layers "F.Cu" "F.Mask" "F.Paste")
			(net "P1V5_BAT")
		)
		(pad "2" smd circle
			(at 0.40005 0 180)
			(size 0 0)
			(layers "F.Cu" "F.Mask" "F.Paste")
			(net "CPU1_VDDBT_RTC_G")
		)
	)
)
